# S9S_MB_2U (Grand Teton) — schematic netlist excerpt (pin names and nets, part order shuffled) for the footprints in the layout excerpt that follows; sources: Cadence DE-HDL packaged netlist, KiCad conversion of 03242023_DA0F0TMBIJ0_F0T_Motherboard_J_brd_V01_OCP.brd

PR170  Q_RES  0 5% CHIP  pkg 0402LF  page 266 : A = SH_PVCCIN_CPU0 ; B = SH_PVCCIN_CPU0_R
R3157  Q_RES  33.2 1% CHIP  pkg 0402LF  page 164 : A = SMB_PEHPCPU1_LVC3_SDA ; B = SMB_PEHPCPU1_LVC3_R3_SDA

(kicad_pcb
	(version 20260206)
	(generator "pcbnew")
	(generator_version "10.0")
	(general
		(thickness 1.6)
		(legacy_teardrops no)
	)
	(paper "A4")
	(title_block
		(title "03242023_DA0F0TMBIJ0_F0T_Motherboard_J_brd_V01_OCP.brd")
		(comment 1 "Grand Teton / footprints 3171-3172 of 6105")
	)
	(layers
		(0 "F.Cu" signal "TOP")
		(4 "In1.Cu" signal "GND")
		(6 "In2.Cu" signal "IN1")
		(8 "In3.Cu" signal "GND1")
		(10 "In4.Cu" signal "IN2")
		(12 "In5.Cu" signal "GND2")
		(14 "In6.Cu" signal "IN3")
		(16 "In7.Cu" signal "GND3")
		(18 "In8.Cu" signal "VCC")
		(20 "In9.Cu" signal "VCC1")
		(22 "In10.Cu" signal "GND4")
		(24 "In11.Cu" signal "IN4")
		(26 "In12.Cu" signal "GND5")
		(28 "In13.Cu" signal "IN5")
		(30 "In14.Cu" signal "GND6")
		(32 "In15.Cu" signal "IN6")
		(34 "In16.Cu" signal "GND7")
		(2 "B.Cu" signal "BOTTOM")
		(9 "F.Adhes" user "F.Adhesive")
		(11 "B.Adhes" user "B.Adhesive")
		(13 "F.Paste" user "Package Geometry/Pastemask Top")
		(15 "B.Paste" user "Package Geometry/Pastemask Bottom")
		(5 "F.SilkS" user "Ref Des/Silkscreen Top")
		(7 "B.SilkS" user "Ref Des/Silkscreen Bottom")
		(1 "F.Mask" user "Board Geometry/Soldermask Top")
		(3 "B.Mask" user "Board Geometry/Soldermask Bottom")
		(17 "Dwgs.User" user "User.Drawings")
		(19 "Cmts.User" user "User.Comments")
		(21 "Eco1.User" user "User.Eco1")
		(23 "Eco2.User" user "User.Eco2")
		(25 "Edge.Cuts" user "Board Geometry/Outline")
		(27 "Margin" user)
		(31 "F.CrtYd" user "Package Geometry/Place Bound Top")
		(29 "B.CrtYd" user "Package Geometry/Place Bound Bottom")
		(35 "F.Fab" user "Ref Des/Assembly Top")
		(33 "B.Fab" user "Ref Des/Assembly Bottom")
	)
	(footprint ""
		(layer "F.Cu")
		(at 351.961704 -353.14509)
		(property "Reference" "PR170"
			(at 0 0 0)
			(layer "F.SilkS")
			(hide yes)
			(effects
				(font
					(size 1.27 1.27)
				)
			)
		)
		(property "Value" ""
			(at 0 0 0)
			(layer "F.Fab")
			(effects
				(font
					(size 1.27 1.27)
				)
			)
		)
		(duplicate_pad_numbers_are_jumpers no)
		(fp_line
			(start -0.7874 -0.4064)
			(end 0.7874 -0.4064)
			(stroke
				(width 0.1524)
				(type default)
			)
			(layer "F.SilkS")
		)
		(fp_line
			(start -0.7874 0.4064)
			(end -0.7874 -0.4064)
			(stroke
				(width 0.1524)
				(type default)
			)
			(layer "F.SilkS")
		)
		(fp_line
			(start 0.7874 -0.4064)
			(end 0.7874 0.4064)
			(stroke
				(width 0.1524)
				(type default)
			)
			(layer "F.SilkS")
		)
		(fp_line
			(start 0.7874 0.4064)
			(end -0.7874 0.4064)
			(stroke
				(width 0.1524)
				(type default)
			)
			(layer "F.SilkS")
		)
		(fp_line
			(start -0.67945 -0.305054)
			(end -0.12065 -0.305054)
			(stroke
				(width 0.1)
				(type default)
			)
			(layer "F.Fab")
		)
		(fp_line
			(start -0.67945 0.3048)
			(end -0.67945 -0.305054)
			(stroke
				(width 0.1)
				(type default)
			)
			(layer "F.Fab")
		)
		(fp_line
			(start -0.12065 -0.305054)
			(end -0.12065 -0.2794)
			(stroke
				(width 0.1)
				(type default)
			)
			(layer "F.Fab")
		)
		(fp_line
			(start -0.12065 -0.2794)
			(end 0.12065 -0.2794)
			(stroke
				(width 0.1)
				(type default)
			)
			(layer "F.Fab")
		)
		(fp_line
			(start -0.12065 0.2794)
			(end -0.12065 0.3048)
			(stroke
				(width 0.1)
				(type default)
			)
			(layer "F.Fab")
		)
		(fp_line
			(start -0.12065 0.3048)
			(end -0.67945 0.3048)
			(stroke
				(width 0.1)
				(type default)
			)
			(layer "F.Fab")
		)
		(fp_line
			(start 0.120396 0.2794)
			(end -0.12065 0.2794)
			(stroke
				(width 0.1)
				(type default)
			)
			(layer "F.Fab")
		)
		(fp_line
			(start 0.120396 0.3048)
			(end 0.120396 0.2794)
			(stroke
				(width 0.1)
				(type default)
			)
			(layer "F.Fab")
		)
		(fp_line
			(start 0.12065 -0.3048)
			(end 0.67945 -0.3048)
			(stroke
				(width 0.1)
				(type default)
			)
			(layer "F.Fab")
		)
		(fp_line
			(start 0.12065 -0.2794)
			(end 0.12065 -0.3048)
			(stroke
				(width 0.1)
				(type default)
			)
			(layer "F.Fab")
		)
		(fp_line
			(start 0.67945 -0.3048)
			(end 0.67945 0.3048)
			(stroke
				(width 0.1)
				(type default)
			)
			(layer "F.Fab")
		)
		(fp_line
			(start 0.67945 0.3048)
			(end 0.120396 0.3048)
			(stroke
				(width 0.1)
				(type default)
			)
			(layer "F.Fab")
		)
		(pad "1" smd circle
			(at -0.40005 0)
			(size 0 0)
			(layers "F.Cu" "F.Mask" "F.Paste")
			(net "SH_PVCCIN_CPU0")
		)
		(pad "2" smd circle
			(at 0.40005 0)
			(size 0 0)
			(layers "F.Cu" "F.Mask" "F.Paste")
			(net "SH_PVCCIN_CPU0_R")
		)
	)
	(footprint ""
		(layer "F.Cu")
		(at 147.08378 -126.291848 180)
		(property "Reference" "R3157"
			(at 0 0 180)
			(layer "F.SilkS")
			(hide yes)
			(effects
				(font
					(size 1.27 1.27)
				)
			)
		)
		(property "Value" ""
			(at 0 0 180)
			(layer "F.Fab")
			(effects
				(font
					(size 1.27 1.27)
				)
			)
		)
		(duplicate_pad_numbers_are_jumpers no)
		(fp_line
			(start 0.7874 0.4064)
			(end -0.7874 0.4064)
			(stroke
				(width 0.1524)
				(type default)
			)
			(layer "F.SilkS")
		)
		(fp_line
			(start 0.7874 -0.4064)
			(end 0.7874 0.4064)
			(stroke
				(width 0.1524)
				(type default)
			)
			(layer "F.SilkS")
		)
		(fp_line
			(start -0.7874 0.4064)
			(end -0.7874 -0.4064)
			(stroke
				(width 0.1524)
				(type default)
			)
			(layer "F.SilkS")
		)
		(fp_line
			(start -0.7874 -0.4064)
			(end 0.7874 -0.4064)
			(stroke
				(width 0.1524)
				(type default)
			)
			(layer "F.SilkS")
		)
		(fp_line
			(start 0.67945 0.3048)
			(end 0.120396 0.3048)
			(stroke
				(width 0.1)
				(type default)
			)
			(layer "F.Fab")
		)
		(fp_line
			(start 0.67945 -0.3048)
			(end 0.67945 0.3048)
			(stroke
				(width 0.1)
				(type default)
			)
			(layer "F.Fab")
		)
		(fp_line
			(start 0.12065 -0.2794)
			(end 0.12065 -0.3048)
			(stroke
				(width 0.1)
				(type default)
			)
			(layer "F.Fab")
		)
		(fp_line
			(start 0.12065 -0.3048)
			(end 0.67945 -0.3048)
			(stroke
				(width 0.1)
				(type default)
			)
			(layer "F.Fab")
		)
		(fp_line
			(start 0.120396 0.3048)
			(end 0.120396 0.2794)
			(stroke
				(width 0.1)
				(type default)
			)
			(layer "F.Fab")
		)
		(fp_line
			(start 0.120396 0.2794)
			(end -0.12065 0.2794)
			(stroke
				(width 0.1)
				(type default)
			)
			(layer "F.Fab")
		)
		(fp_line
			(start -0.12065 0.3048)
			(end -0.67945 0.3048)
			(stroke
				(width 0.1)
				(type default)
			)
			(layer "F.Fab")
		)
		(fp_line
			(start -0.12065 0.2794)
			(end -0.12065 0.3048)
			(stroke
				(width 0.1)
				(type default)
			)
			(layer "F.Fab")
		)
		(fp_line
			(start -0.12065 -0.2794)
			(end 0.12065 -0.2794)
			(stroke
				(width 0.1)
				(type default)
			)
			(layer "F.Fab")
		)
		(fp_line
			(start -0.12065 -0.305054)
			(end -0.12065 -0.2794)
			(stroke
				(width 0.1)
				(type default)
			)
			(layer "F.Fab")
		)
		(fp_line
			(start -0.67945 0.3048)
			(end -0.67945 -0.305054)
			(stroke
				(width 0.1)
				(type default)
			)
			(layer "F.Fab")
		)
		(fp_line
			(start -0.67945 -0.305054)
			(end -0.12065 -0.305054)
			(stroke
				(width 0.1)
				(type default)
			)
			(layer "F.Fab")
		)
		(pad "1" smd circle
			(at -0.40005 0 180)
			(size 0 0)
			(layers "F.Cu" "F.Mask" "F.Paste")
			(net "SMB_PEHPCPU1_LVC3_SDA")
		)
		(pad "2" smd circle
			(at 0.40005 0 180)
			(size 0 0)
			(layers "F.Cu" "F.Mask" "F.Paste")
			(net "SMB_PEHPCPU1_LVC3_R3_SDA")
		)
	)
)
